(kicad_pcb
	(version 20260206)
	(generator "pcbnew")
	(generator_version "10.0")
	(general
		(thickness 1.6)
		(legacy_teardrops no)
	)
	(paper "A4")
	(title_block
		(title "dpb — 14545-sa.0730WZS0815.brd")
		(comment 1 "Honey Badger (Wiwynn) / footprints 203-210 of 1066")
	)
	(layers
		(0 "F.Cu" signal "TOP")
		(4 "In1.Cu" signal "L2GND")
		(6 "In2.Cu" signal "L3")
		(8 "In3.Cu" signal "L4VCC")
		(10 "In4.Cu" signal "L5VCC")
		(12 "In5.Cu" signal "L6")
		(14 "In6.Cu" signal "L7GND")
		(2 "B.Cu" signal "BOTTOM")
		(9 "F.Adhes" user "F.Adhesive")
		(11 "B.Adhes" user "B.Adhesive")
		(13 "F.Paste" user "Package Geometry/Pastemask Top")
		(15 "B.Paste" user "Package Geometry/Pastemask Bottom")
		(5 "F.SilkS" user "Ref Des/Silkscreen Top")
		(7 "B.SilkS" user "Ref Des/Silkscreen Bottom")
		(1 "F.Mask" user "Board Geometry/Soldermask Top")
		(3 "B.Mask" user "Board Geometry/Soldermask Bottom")
		(17 "Dwgs.User" user "User.Drawings")
		(19 "Cmts.User" user "User.Comments")
		(21 "Eco1.User" user "User.Eco1")
		(23 "Eco2.User" user "User.Eco2")
		(25 "Edge.Cuts" user "Board Geometry/Outline")
		(27 "Margin" user)
		(31 "F.CrtYd" user "Package Geometry/Place Bound Top")
		(29 "B.CrtYd" user "Package Geometry/Place Bound Bottom")
		(35 "F.Fab" user "Ref Des/Assembly Top")
		(33 "B.Fab" user "Ref Des/Assembly Bottom")
	)
	(footprint ""
		(layer "F.Cu")
		(at 205.951074 -178.905662 90)
		(property "Reference" "Q7"
			(at 0 0 90)
			(layer "F.SilkS")
			(hide yes)
			(effects
				(font
					(size 1.27 1.27)
				)
			)
		)
		(property "Value" "AO4406AL-GP"
			(at -3.707384 -1.5367 90)
			(unlocked yes)
			(layer "F.Fab")
			(hide yes)
			(effects
				(font
					(size 1.016 1.016)
					(thickness 0.1524)
				)
			)
		)
		(property "Device Type" "SOIC8H69"
			(at -3.707384 -3.0607 90)
			(unlocked yes)
			(layer "F.Fab")
			(hide yes)
			(effects
				(font
					(size 1.016 1.016)
					(thickness 0.1524)
				)
			)
		)
		(duplicate_pad_numbers_are_jumpers no)
		(fp_line
			(start 2.1336 -1.4224)
			(end -2.7432 -1.4224)
			(stroke
				(width 0.1524)
				(type default)
			)
			(layer "F.SilkS")
		)
		(fp_line
			(start -2.7432 -1.4224)
			(end -2.7432 1.4224)
			(stroke
				(width 0.1524)
				(type default)
			)
			(layer "F.SilkS")
		)
		(fp_line
			(start -2.7178 -0.508)
			(end -2.1844 -0.0508)
			(stroke
				(width 0.1524)
				(type default)
			)
			(layer "F.SilkS")
		)
		(fp_line
			(start -2.1844 -0.0508)
			(end -2.7178 0.508)
			(stroke
				(width 0.1524)
				(type default)
			)
			(layer "F.SilkS")
		)
		(fp_line
			(start 2.1336 1.4224)
			(end 2.1336 -1.4224)
			(stroke
				(width 0.1524)
				(type default)
			)
			(layer "F.SilkS")
		)
		(fp_line
			(start -2.7432 1.4224)
			(end 2.1336 1.4224)
			(stroke
				(width 0.1524)
				(type default)
			)
			(layer "F.SilkS")
		)
		(fp_line
			(start -2.7432 1.4224)
			(end -2.6416 1.4224)
			(stroke
				(width 0.1524)
				(type default)
			)
			(layer "F.SilkS")
		)
		(fp_line
			(start -2.6289 3.4417)
			(end -2.6289 1.4732)
			(stroke
				(width 0.381)
				(type default)
			)
			(layer "F.SilkS")
		)
		(fp_poly
			(pts
				(xy -2.2098 -1.4224) (xy -2.2098 1.4224) (xy 2.2098 1.4224) (xy 2.2098 -1.4224)
			)
			(stroke
				(width 0)
				(type default)
			)
			(fill yes)
			(layer "F.SilkS")
		)
		(fp_rect
			(start -2.450084 2.999994)
			(end 2.450084 -2.999994)
			(stroke
				(width 0)
				(type default)
			)
			(fill no)
			(layer "F.CrtYd")
		)
		(fp_poly
			(pts
				(xy -2.8194 3.6322) (xy -2.8194 -3.6322) (xy 2.8194 -3.6322) (xy 2.8194 1.18364) (xy 2.450084 1.18364)
				(xy 2.450084 -2.999994) (xy -2.450084 -2.999994) (xy -2.450084 2.999994) (xy 2.450084 2.999994)
				(xy 2.450084 1.18618) (xy 2.8194 1.18618) (xy 2.8194 3.6322)
			)
			(stroke
				(width 0)
				(type default)
			)
			(fill no)
			(layer "F.CrtYd")
		)
		(fp_rect
			(start -2.8194 3.6322)
			(end 2.8194 -3.6322)
			(stroke
				(width 0)
				(type default)
			)
			(fill no)
			(layer "F.Fab")
		)
		(pad "1" smd rect
			(at -1.905 2.54 90)
			(size 0.635 1.651)
			(layers "F.Cu" "F.Mask" "F.Paste")
			(net "P5V_HDD3")
		)
		(pad "2" smd rect
			(at -0.635 2.54 90)
			(size 0.635 1.651)
			(layers "F.Cu" "F.Mask" "F.Paste")
			(net "P5V_HDD3")
		)
		(pad "3" smd rect
			(at 0.635 2.54 90)
			(size 0.635 1.651)
			(layers "F.Cu" "F.Mask" "F.Paste")
			(net "P5V_HDD3")
		)
		(pad "4" smd rect
			(at 1.905 2.54 90)
			(size 0.635 1.651)
			(layers "F.Cu" "F.Mask" "F.Paste")
			(net "SW_HDD3_P")
		)
		(pad "5" smd rect
			(at 1.905 -2.54 90)
			(size 0.635 1.651)
			(layers "F.Cu" "F.Mask" "F.Paste")
			(net "P5VA")
		)
		(pad "6" smd rect
			(at 0.635 -2.54 90)
			(size 0.635 1.651)
			(layers "F.Cu" "F.Mask" "F.Paste")
			(net "P5VA")
		)
		(pad "7" smd rect
			(at -0.635 -2.54 90)
			(size 0.635 1.651)
			(layers "F.Cu" "F.Mask" "F.Paste")
			(net "P5VA")
		)
		(pad "8" smd rect
			(at -1.905 -2.54 90)
			(size 0.635 1.651)
			(layers "F.Cu" "F.Mask" "F.Paste")
			(net "P5VA")
		)
	)
	(footprint ""
		(layer "F.Cu")
		(at 25.971246 -374.9167 -90)
		(property "Reference" "R320"
			(at 0 0 270)
			(layer "F.SilkS")
			(hide yes)
			(effects
				(font
					(size 1.27 1.27)
				)
			)
		)
		(property "Value" "4K7R2J-2-GP"
			(at 0.064008 -3.993896 270)
			(unlocked yes)
			(layer "F.Fab")
			(hide yes)
			(effects
				(font
					(size 1.016 1.016)
					(thickness 0.1524)
				)
			)
		)
		(property "Device Type" "R402H16"
			(at 0.064008 -5.517896 270)
			(unlocked yes)
			(layer "F.Fab")
			(hide yes)
			(effects
				(font
					(size 1.016 1.016)
					(thickness 0.1524)
				)
			)
		)
		(duplicate_pad_numbers_are_jumpers no)
		(fp_line
			(start -0.508 -0.9398)
			(end -0.508 0.9398)
			(stroke
				(width 0.1524)
				(type default)
			)
			(layer "F.SilkS")
		)
		(fp_line
			(start 0.508 -0.9398)
			(end -0.508 -0.9398)
			(stroke
				(width 0.1524)
				(type default)
			)
			(layer "F.SilkS")
		)
		(fp_rect
			(start -0.508 0.9398)
			(end 0.508 -0.9398)
			(stroke
				(width 0)
				(type default)
			)
			(fill no)
			(layer "F.CrtYd")
		)
		(fp_rect
			(start -0.508 0.9398)
			(end 0.508 -0.9398)
			(stroke
				(width 0)
				(type default)
			)
			(fill no)
			(layer "F.Fab")
		)
		(pad "1" smd custom
			(at 0 -0.4445 270)
			(size 0.1397 0.1397)
			(layers "F.Cu" "F.Mask" "F.Paste")
			(net "I2C_B_TMP1_A2")
			(options
				(clearance outline)
				(anchor circle)
			)
			(primitives
				(gr_poly
					(pts
						(arc
							(start -0.1778 -0.2794)
							(mid -0.249642 -0.249642)
							(end -0.2794 -0.1778)
						)
						(arc
							(start -0.2794 0.1778)
							(mid -0.249642 0.249642)
							(end -0.1778 0.2794)
						)
						(arc
							(start 0.1778 0.2794)
							(mid 0.249642 0.249642)
							(end 0.2794 0.1778)
						)
						(arc
							(start 0.2794 -0.1778)
							(mid 0.249642 -0.249642)
							(end 0.1778 -0.2794)
						)
					)
					(width 0)
					(fill yes)
				)
			)
		)
		(pad "2" smd custom
			(at 0 0.4445 270)
			(size 0.1397 0.1397)
			(layers "F.Cu" "F.Mask" "F.Paste")
			(net "GND")
			(options
				(clearance outline)
				(anchor circle)
			)
			(primitives
				(gr_poly
					(pts
						(arc
							(start -0.1778 -0.2794)
							(mid -0.249642 -0.249642)
							(end -0.2794 -0.1778)
						)
						(arc
							(start -0.2794 0.1778)
							(mid -0.249642 0.249642)
							(end -0.1778 0.2794)
						)
						(arc
							(start 0.1778 0.2794)
							(mid 0.249642 0.249642)
							(end 0.2794 0.1778)
						)
						(arc
							(start 0.2794 -0.1778)
							(mid 0.249642 -0.249642)
							(end 0.1778 -0.2794)
						)
					)
					(width 0)
					(fill yes)
				)
			)
		)
	)
	(footprint ""
		(layer "F.Cu")
		(at 55.117492 -72.545956)
		(property "Reference" "C254"
			(at 0 0 0)
			(layer "F.SilkS")
			(hide yes)
			(effects
				(font
					(size 1.27 1.27)
				)
			)
		)
		(property "Value" "SCD01U50V2KX-1GP"
			(at 1.1811 -2.7051 0)
			(unlocked yes)
			(layer "F.Fab")
			(hide yes)
			(effects
				(font
					(size 1.016 1.016)
					(thickness 0.1524)
				)
			)
		)
		(property "Device Type" "C402H22"
			(at 1.1811 -4.2291 0)
			(unlocked yes)
			(layer "F.Fab")
			(hide yes)
			(effects
				(font
					(size 1.016 1.016)
					(thickness 0.1524)
				)
			)
		)
		(duplicate_pad_numbers_are_jumpers no)
		(fp_rect
			(start -0.4318 0.9525)
			(end 0.4318 -0.9525)
			(stroke
				(width 0)
				(type default)
			)
			(fill no)
			(layer "F.CrtYd")
		)
		(fp_rect
			(start -0.4318 0.9525)
			(end 0.4318 -0.9525)
			(stroke
				(width 0)
				(type default)
			)
			(fill no)
			(layer "F.Fab")
		)
		(pad "1" smd custom
			(at 0 -0.4445)
			(size 0.1524 0.1524)
			(layers "F.Cu" "F.Mask" "F.Paste")
			(net "HDD_PRSNT_NET9")
			(options
				(clearance outline)
				(anchor circle)
			)
			(primitives
				(gr_poly
					(pts
						(arc
							(start 0.3048 -0.2032)
							(mid 0.275042 -0.275042)
							(end 0.2032 -0.3048)
						)
						(arc
							(start -0.2032 -0.3048)
							(mid -0.275042 -0.275042)
							(end -0.3048 -0.2032)
						)
						(arc
							(start -0.3048 0.2032)
							(mid -0.275042 0.275042)
							(end -0.2032 0.3048)
						)
						(arc
							(start 0.2032 0.3048)
							(mid 0.275042 0.275042)
							(end 0.3048 0.2032)
						)
					)
					(width 0)
					(fill yes)
				)
			)
		)
		(pad "2" smd custom
			(at 0 0.4445)
			(size 0.1524 0.1524)
			(layers "F.Cu" "F.Mask" "F.Paste")
			(net "GND")
			(options
				(clearance outline)
				(anchor circle)
			)
			(primitives
				(gr_poly
					(pts
						(arc
							(start 0.3048 -0.2032)
							(mid 0.275042 -0.275042)
							(end 0.2032 -0.3048)
						)
						(arc
							(start -0.2032 -0.3048)
							(mid -0.275042 -0.275042)
							(end -0.3048 -0.2032)
						)
						(arc
							(start -0.3048 0.2032)
							(mid -0.275042 0.275042)
							(end -0.2032 0.3048)
						)
						(arc
							(start 0.2032 0.3048)
							(mid 0.275042 0.275042)
							(end 0.3048 0.2032)
						)
					)
					(width 0)
					(fill yes)
				)
			)
		)
	)
	(footprint ""
		(layer "F.Cu")
		(at 193.216784 -187.930028 -90)
		(property "Reference" "Q8"
			(at 0 0 270)
			(layer "F.SilkS")
			(hide yes)
			(effects
				(font
					(size 1.27 1.27)
				)
			)
		)
		(property "Value" "2N7002DW-7F-GP"
			(at -2.3622 -8.2042 270)
			(unlocked yes)
			(layer "F.Fab")
			(hide yes)
			(effects
				(font
					(size 1.016 1.016)
					(thickness 0.1524)
				)
			)
		)
		(property "Device Type" "SOT-363H44"
			(at -2.3622 -10.1092 270)
			(unlocked yes)
			(layer "F.Fab")
			(hide yes)
			(effects
				(font
					(size 1.016 1.016)
					(thickness 0.1524)
				)
			)
		)
		(duplicate_pad_numbers_are_jumpers no)
		(fp_line
			(start -1.4478 1.7018)
			(end 1.4478 1.7018)
			(stroke
				(width 0.1524)
				(type default)
			)
			(layer "F.SilkS")
		)
		(fp_line
			(start 1.4478 1.7018)
			(end 1.4478 -1.7018)
			(stroke
				(width 0.1524)
				(type default)
			)
			(layer "F.SilkS")
		)
		(fp_line
			(start -1.27 1.524)
			(end -1.27 0.6604)
			(stroke
				(width 0.4826)
				(type default)
			)
			(layer "F.SilkS")
		)
		(fp_line
			(start -1.4478 -1.7018)
			(end -1.4478 1.7018)
			(stroke
				(width 0.1524)
				(type default)
			)
			(layer "F.SilkS")
		)
		(fp_line
			(start 1.4478 -1.7018)
			(end -1.4478 -1.7018)
			(stroke
				(width 0.1524)
				(type default)
			)
			(layer "F.SilkS")
		)
		(fp_poly
			(pts
				(xy -1.524 -1.778) (xy 1.524 -1.778) (xy 1.524 1.778) (xy -1.524 1.778)
			)
			(stroke
				(width 0)
				(type default)
			)
			(fill no)
			(layer "F.CrtYd")
		)
		(fp_poly
			(pts
				(xy -1.524 -1.778) (xy 1.524 -1.778) (xy 1.524 1.778) (xy -1.524 1.778)
			)
			(stroke
				(width 0)
				(type default)
			)
			(fill no)
			(layer "F.Fab")
		)
		(pad "1" smd rect
			(at -0.65024 0.9398 270)
			(size 0.4064 1.016)
			(layers "F.Cu" "F.Mask" "F.Paste")
			(net "GND")
		)
		(pad "2" smd rect
			(at 0 0.9398 270)
			(size 0.4064 1.016)
			(layers "F.Cu" "F.Mask" "F.Paste")
			(net "SW_PWR_R_HDD3")
		)
		(pad "3" smd rect
			(at 0.65024 0.9398 270)
			(size 0.4064 1.016)
			(layers "F.Cu" "F.Mask" "F.Paste")
			(net "SW_HDD3_P")
		)
		(pad "4" smd rect
			(at 0.65024 -0.9398 270)
			(size 0.4064 1.016)
			(layers "F.Cu" "F.Mask" "F.Paste")
			(net "GND")
		)
		(pad "5" smd rect
			(at 0 -0.9398 270)
			(size 0.4064 1.016)
			(layers "F.Cu" "F.Mask" "F.Paste")
			(net "SW_HDD3_G")
		)
		(pad "6" smd rect
			(at -0.65024 -0.9398 270)
			(size 0.4064 1.016)
			(layers "F.Cu" "F.Mask" "F.Paste")
			(net "SW_HDD3_R")
		)
	)
	(footprint ""
		(layer "F.Cu")
		(at 227.499926 -350.160082 180)
		(property "Reference" "LED2"
			(at 0 0 180)
			(layer "F.SilkS")
			(hide yes)
			(effects
				(font
					(size 1.27 1.27)
				)
			)
		)
		(property "Value" "LED-RB-4-GP"
			(at 5.88899 1.80848 180)
			(unlocked yes)
			(layer "F.Fab")
			(hide yes)
			(effects
				(font
					(size 1.016 1.016)
					(thickness 0.1524)
				)
			)
		)
		(property "Device Type" "LED1613-4PH20"
			(at 5.88899 0.28448 180)
			(unlocked yes)
			(layer "F.Fab")
			(hide yes)
			(effects
				(font
					(size 1.016 1.016)
					(thickness 0.1524)
				)
			)
		)
		(duplicate_pad_numbers_are_jumpers no)
		(fp_line
			(start 1.4478 0.9652)
			(end -1.4478 0.9652)
			(stroke
				(width 0.1524)
				(type default)
			)
			(layer "F.SilkS")
		)
		(fp_line
			(start 1.4478 -0.9652)
			(end 1.4478 0.9652)
			(stroke
				(width 0.1524)
				(type default)
			)
			(layer "F.SilkS")
		)
		(fp_line
			(start -1.4478 0.9652)
			(end -1.4478 -0.9652)
			(stroke
				(width 0.1524)
				(type default)
			)
			(layer "F.SilkS")
		)
		(fp_line
			(start -1.4478 0.9652)
			(end -1.4478 -0.9652)
			(stroke
				(width 0.508)
				(type default)
			)
			(layer "F.SilkS")
		)
		(fp_line
			(start -1.4478 -0.9652)
			(end 1.4478 -0.9652)
			(stroke
				(width 0.1524)
				(type default)
			)
			(layer "F.SilkS")
		)
		(fp_rect
			(start -0.8001 0.6477)
			(end 0.8001 -0.6477)
			(stroke
				(width 0)
				(type default)
			)
			(fill no)
			(layer "F.CrtYd")
		)
		(fp_poly
			(pts
				(xy -1.7018 1.2192) (xy -1.7018 -0.06223) (xy -0.8001 -0.06223) (xy -0.8001 0.6477) (xy 0.8001 0.6477)
				(xy 0.8001 -0.6477) (xy -0.8001 -0.6477) (xy -0.8001 -0.0635) (xy -1.7018 -0.0635) (xy -1.7018 -1.2192)
				(xy 1.7018 -1.2192) (xy 1.7018 1.2192)
			)
			(stroke
				(width 0)
				(type default)
			)
			(fill no)
			(layer "F.CrtYd")
		)
		(fp_rect
			(start -1.7018 1.2192)
			(end 1.7018 -1.2192)
			(stroke
				(width 0)
				(type default)
			)
			(fill no)
			(layer "F.Fab")
		)
		(pad "1" smd rect
			(at -0.73025 0.4064 180)
			(size 0.9144 0.6096)
			(layers "F.Cu" "F.Mask" "F.Paste")
			(net "DRV_ACT_NET1")
		)
		(pad "2" smd rect
			(at -0.73025 -0.4064 180)
			(size 0.9144 0.6096)
			(layers "F.Cu" "F.Mask" "F.Paste")
			(net "FLT_NET_HDD1")
		)
		(pad "3" smd rect
			(at 0.73025 -0.4064 180)
			(size 0.9144 0.6096)
			(layers "F.Cu" "F.Mask" "F.Paste")
			(net "FLT_HDD1")
		)
		(pad "4" smd rect
			(at 0.73025 0.4064 180)
			(size 0.9144 0.6096)
			(layers "F.Cu" "F.Mask" "F.Paste")
			(net "DRV_ACT_1")
		)
	)
	(footprint ""
		(layer "F.Cu")
		(at 41.275 -141.605 -90)
		(property "Reference" "TP2"
			(at 0 0 270)
			(layer "F.SilkS")
			(hide yes)
			(effects
				(font
					(size 1.27 1.27)
				)
			)
		)
		(property "Value" "TPAD32-GP"
			(at 0 -3.166364 270)
			(unlocked yes)
			(layer "F.Fab")
			(hide yes)
			(effects
				(font
					(size 1.016 1.016)
					(thickness 0.1524)
				)
			)
		)
		(property "Device Type" "TPAD32"
			(at 0 -4.690618 270)
			(unlocked yes)
			(layer "F.Fab")
			(hide yes)
			(effects
				(font
					(size 1.016 1.016)
					(thickness 0.1524)
				)
			)
		)
		(duplicate_pad_numbers_are_jumpers no)
		(fp_poly
			(pts
				(arc
					(start 0 -0.4064)
					(mid 0 0.4064)
					(end 0 -0.4064)
				)
			)
			(stroke
				(width 0)
				(type default)
			)
			(fill no)
			(layer "F.CrtYd")
		)
		(fp_poly
			(pts
				(arc
					(start 0 -0.7112)
					(mid 0 0.7112)
					(end 0 -0.7112)
				)
			)
			(stroke
				(width 0)
				(type default)
			)
			(fill no)
			(layer "F.Fab")
		)
		(pad "1" smd circle
			(at 0 0 270)
			(size 0.8128 0.8128)
			(layers "F.Cu" "F.Mask" "F.Paste")
			(net "I2C_B_TMP2_ALERT")
		)
	)
	(footprint ""
		(layer "F.Cu")
		(at 209.422746 -52.0827 -90)
		(property "Reference" "TP4"
			(at 0 0 270)
			(layer "F.SilkS")
			(hide yes)
			(effects
				(font
					(size 1.27 1.27)
				)
			)
		)
		(property "Value" "TPAD32-GP"
			(at 0 -3.166364 270)
			(unlocked yes)
			(layer "F.Fab")
			(hide yes)
			(effects
				(font
					(size 1.016 1.016)
					(thickness 0.1524)
				)
			)
		)
		(property "Device Type" "TPAD32"
			(at 0 -4.690618 270)
			(unlocked yes)
			(layer "F.Fab")
			(hide yes)
			(effects
				(font
					(size 1.016 1.016)
					(thickness 0.1524)
				)
			)
		)
		(duplicate_pad_numbers_are_jumpers no)
		(fp_poly
			(pts
				(arc
					(start 0 -0.4064)
					(mid 0 0.4064)
					(end 0 -0.4064)
				)
			)
			(stroke
				(width 0)
				(type default)
			)
			(fill no)
			(layer "F.CrtYd")
		)
		(fp_poly
			(pts
				(arc
					(start 0 -0.7112)
					(mid 0 0.7112)
					(end 0 -0.7112)
				)
			)
			(stroke
				(width 0)
				(type default)
			)
			(fill no)
			(layer "F.Fab")
		)
		(pad "1" smd circle
			(at 0 0 270)
			(size 0.8128 0.8128)
			(layers "F.Cu" "F.Mask" "F.Paste")
			(net "I2C_B_TMP4_ALERT")
		)
	)
	(footprint ""
		(layer "F.Cu")
		(at 59.943746 -17.6657 90)
		(property "Reference" "PC16"
			(at 0 0 90)
			(layer "F.SilkS")
			(hide yes)
			(effects
				(font
					(size 1.27 1.27)
				)
			)
		)
		(property "Value" "SC22U25V5MX-GP"
			(at -0.0762 -6.1214 90)
			(unlocked yes)
			(layer "F.Fab")
			(hide yes)
			(effects
				(font
					(size 1.016 1.016)
					(thickness 0.1524)
				)
			)
		)
		(property "Device Type" "C805H58"
			(at -0.0762 -8.1534 90)
			(unlocked yes)
			(layer "F.Fab")
			(hide yes)
			(effects
				(font
					(size 1.016 1.016)
					(thickness 0.1524)
				)
			)
		)
		(duplicate_pad_numbers_are_jumpers no)
		(fp_line
			(start 0.635 0)
			(end -0.635 0)
			(stroke
				(width 0.508)
				(type default)
			)
			(layer "F.SilkS")
		)
		(fp_rect
			(start -0.9652 1.778)
			(end 0.9652 -1.778)
			(stroke
				(width 0)
				(type default)
			)
			(fill no)
			(layer "F.CrtYd")
		)
		(fp_poly
			(pts
				(xy -0.9652 -1.778) (xy 0.9652 -1.778) (xy 0.9652 1.778) (xy -0.9652 1.778)
			)
			(stroke
				(width 0)
				(type default)
			)
			(fill no)
			(layer "F.Fab")
		)
		(pad "1" smd rect
			(at 0 -0.9652 90)
			(size 1.397 1.143)
			(layers "F.Cu" "F.Mask" "F.Paste")
			(net "P5VB_12VIN")
		)
		(pad "2" smd rect
			(at 0 0.9652 90)
			(size 1.397 1.143)
			(layers "F.Cu" "F.Mask" "F.Paste")
			(net "GND")
		)
	)
)
